(kicad_pcb
	(version 20260206)
	(generator "pcbnew")
	(generator_version "10.0")
	(general
		(thickness 1.6)
		(legacy_teardrops no)
	)
	(paper "A4")
	(title_block
		(title "01162023_DA0F0TEBIF0_F0T_Expander_BD_F_brd_V02_OCP.brd")
		(comment 1 "Grand Teton / footprints 8425-8431 of 9728")
	)
	(layers
		(0 "F.Cu" signal "TOP")
		(4 "In1.Cu" signal "GND")
		(6 "In2.Cu" signal "VCC")
		(8 "In3.Cu" signal "VCC1")
		(10 "In4.Cu" signal "GND1")
		(12 "In5.Cu" signal "IN1")
		(14 "In6.Cu" signal "GND2")
		(16 "In7.Cu" signal "IN2")
		(18 "In8.Cu" signal "GND3")
		(20 "In9.Cu" signal "IN3")
		(22 "In10.Cu" signal "GND4")
		(24 "In11.Cu" signal "IN4")
		(26 "In12.Cu" signal "GND5")
		(28 "In13.Cu" signal "IN5")
		(30 "In14.Cu" signal "GND6")
		(32 "In15.Cu" signal "IN6")
		(34 "In16.Cu" signal "GND7")
		(2 "B.Cu" signal "BOTTOM")
		(9 "F.Adhes" user "F.Adhesive")
		(11 "B.Adhes" user "B.Adhesive")
		(13 "F.Paste" user "Package Geometry/Pastemask Top")
		(15 "B.Paste" user "Package Geometry/Pastemask Bottom")
		(5 "F.SilkS" user "Ref Des/Silkscreen Top")
		(7 "B.SilkS" user "Ref Des/Silkscreen Bottom")
		(1 "F.Mask" user "Board Geometry/Soldermask Top")
		(3 "B.Mask" user "Board Geometry/Soldermask Bottom")
		(17 "Dwgs.User" user "User.Drawings")
		(19 "Cmts.User" user "User.Comments")
		(21 "Eco1.User" user "User.Eco1")
		(23 "Eco2.User" user "User.Eco2")
		(25 "Edge.Cuts" user "Board Geometry/Outline")
		(27 "Margin" user)
		(31 "F.CrtYd" user "Package Geometry/Place Bound Top")
		(29 "B.CrtYd" user "Package Geometry/Place Bound Bottom")
		(35 "F.Fab" user "Ref Des/Assembly Top")
		(33 "B.Fab" user "Ref Des/Assembly Bottom")
	)
	(footprint ""
		(layer "B.Cu")
		(at 344.87231 -258.004564 90)
		(property "Reference" "PR142"
			(at 0 0 90)
			(layer "B.SilkS")
			(hide yes)
			(effects
				(font
					(size 1.27 1.27)
				)
				(justify mirror)
			)
		)
		(property "Value" ""
			(at 0 0 90)
			(layer "B.Fab")
			(effects
				(font
					(size 1.27 1.27)
				)
				(justify mirror)
			)
		)
		(duplicate_pad_numbers_are_jumpers no)
		(fp_line
			(start 0.7874 -0.4064)
			(end -0.7874 -0.4064)
			(stroke
				(width 0.1524)
				(type default)
			)
			(layer "B.SilkS")
		)
		(fp_line
			(start -0.7874 -0.4064)
			(end -0.7874 0.4064)
			(stroke
				(width 0.1524)
				(type default)
			)
			(layer "B.SilkS")
		)
		(fp_line
			(start 0.7874 0.4064)
			(end 0.7874 -0.4064)
			(stroke
				(width 0.1524)
				(type default)
			)
			(layer "B.SilkS")
		)
		(fp_line
			(start -0.7874 0.4064)
			(end 0.7874 0.4064)
			(stroke
				(width 0.1524)
				(type default)
			)
			(layer "B.SilkS")
		)
		(fp_line
			(start 0.67945 -0.305054)
			(end 0.12065 -0.305054)
			(stroke
				(width 0.1)
				(type default)
			)
			(layer "B.Fab")
		)
		(fp_line
			(start 0.12065 -0.305054)
			(end 0.12065 -0.2794)
			(stroke
				(width 0.1)
				(type default)
			)
			(layer "B.Fab")
		)
		(fp_line
			(start -0.12065 -0.3048)
			(end -0.67945 -0.3048)
			(stroke
				(width 0.1)
				(type default)
			)
			(layer "B.Fab")
		)
		(fp_line
			(start -0.67945 -0.3048)
			(end -0.67945 0.3048)
			(stroke
				(width 0.1)
				(type default)
			)
			(layer "B.Fab")
		)
		(fp_line
			(start 0.12065 -0.2794)
			(end -0.12065 -0.2794)
			(stroke
				(width 0.1)
				(type default)
			)
			(layer "B.Fab")
		)
		(fp_line
			(start -0.12065 -0.2794)
			(end -0.12065 -0.3048)
			(stroke
				(width 0.1)
				(type default)
			)
			(layer "B.Fab")
		)
		(fp_line
			(start 0.12065 0.2794)
			(end 0.12065 0.3048)
			(stroke
				(width 0.1)
				(type default)
			)
			(layer "B.Fab")
		)
		(fp_line
			(start -0.120396 0.2794)
			(end 0.12065 0.2794)
			(stroke
				(width 0.1)
				(type default)
			)
			(layer "B.Fab")
		)
		(fp_line
			(start 0.67945 0.3048)
			(end 0.67945 -0.305054)
			(stroke
				(width 0.1)
				(type default)
			)
			(layer "B.Fab")
		)
		(fp_line
			(start 0.12065 0.3048)
			(end 0.67945 0.3048)
			(stroke
				(width 0.1)
				(type default)
			)
			(layer "B.Fab")
		)
		(fp_line
			(start -0.120396 0.3048)
			(end -0.120396 0.2794)
			(stroke
				(width 0.1)
				(type default)
			)
			(layer "B.Fab")
		)
		(fp_line
			(start -0.67945 0.3048)
			(end -0.120396 0.3048)
			(stroke
				(width 0.1)
				(type default)
			)
			(layer "B.Fab")
		)
		(pad "1" smd circle
			(at 0.40005 0 270)
			(size 0 0)
			(layers "B.Cu" "B.Mask" "B.Paste")
			(net "P12V_AUX")
		)
		(pad "2" smd circle
			(at -0.40005 0 270)
			(size 0 0)
			(layers "B.Cu" "B.Mask" "B.Paste")
			(net "P0V8_PEX2_IINSEN")
		)
	)
	(footprint ""
		(layer "B.Cu")
		(at 261.32282 -87.031576 90)
		(property "Reference" "C2645"
			(at 0 0 90)
			(layer "B.SilkS")
			(hide yes)
			(effects
				(font
					(size 1.27 1.27)
				)
				(justify mirror)
			)
		)
		(property "Value" ""
			(at 0 0 90)
			(layer "B.Fab")
			(effects
				(font
					(size 1.27 1.27)
				)
				(justify mirror)
			)
		)
		(duplicate_pad_numbers_are_jumpers no)
		(fp_line
			(start 0.7874 -0.4064)
			(end -0.7874 -0.4064)
			(stroke
				(width 0.1524)
				(type default)
			)
			(layer "B.SilkS")
		)
		(fp_line
			(start -0.7874 -0.4064)
			(end -0.7874 0.4064)
			(stroke
				(width 0.1524)
				(type default)
			)
			(layer "B.SilkS")
		)
		(fp_line
			(start 0.7874 0.4064)
			(end 0.7874 -0.4064)
			(stroke
				(width 0.1524)
				(type default)
			)
			(layer "B.SilkS")
		)
		(fp_line
			(start -0.7874 0.4064)
			(end 0.7874 0.4064)
			(stroke
				(width 0.1524)
				(type default)
			)
			(layer "B.SilkS")
		)
		(fp_line
			(start 0.67945 -0.305054)
			(end 0.12065 -0.305054)
			(stroke
				(width 0.1)
				(type default)
			)
			(layer "B.Fab")
		)
		(fp_line
			(start 0.12065 -0.305054)
			(end 0.12065 -0.2794)
			(stroke
				(width 0.1)
				(type default)
			)
			(layer "B.Fab")
		)
		(fp_line
			(start -0.12065 -0.3048)
			(end -0.67945 -0.3048)
			(stroke
				(width 0.1)
				(type default)
			)
			(layer "B.Fab")
		)
		(fp_line
			(start -0.67945 -0.3048)
			(end -0.67945 0.3048)
			(stroke
				(width 0.1)
				(type default)
			)
			(layer "B.Fab")
		)
		(fp_line
			(start 0.12065 -0.2794)
			(end -0.12065 -0.2794)
			(stroke
				(width 0.1)
				(type default)
			)
			(layer "B.Fab")
		)
		(fp_line
			(start -0.12065 -0.2794)
			(end -0.12065 -0.3048)
			(stroke
				(width 0.1)
				(type default)
			)
			(layer "B.Fab")
		)
		(fp_line
			(start 0.12065 0.2794)
			(end 0.12065 0.3048)
			(stroke
				(width 0.1)
				(type default)
			)
			(layer "B.Fab")
		)
		(fp_line
			(start -0.120396 0.2794)
			(end 0.12065 0.2794)
			(stroke
				(width 0.1)
				(type default)
			)
			(layer "B.Fab")
		)
		(fp_line
			(start 0.67945 0.3048)
			(end 0.67945 -0.305054)
			(stroke
				(width 0.1)
				(type default)
			)
			(layer "B.Fab")
		)
		(fp_line
			(start 0.12065 0.3048)
			(end 0.67945 0.3048)
			(stroke
				(width 0.1)
				(type default)
			)
			(layer "B.Fab")
		)
		(fp_line
			(start -0.120396 0.3048)
			(end -0.120396 0.2794)
			(stroke
				(width 0.1)
				(type default)
			)
			(layer "B.Fab")
		)
		(fp_line
			(start -0.67945 0.3048)
			(end -0.120396 0.3048)
			(stroke
				(width 0.1)
				(type default)
			)
			(layer "B.Fab")
		)
		(pad "1" smd circle
			(at 0.40005 0 270)
			(size 0 0)
			(layers "B.Cu" "B.Mask" "B.Paste")
			(net "P3V3_CLK_GEN_VDDMXCK_CK440")
		)
		(pad "2" smd circle
			(at -0.40005 0 270)
			(size 0 0)
			(layers "B.Cu" "B.Mask" "B.Paste")
			(net "GND")
		)
	)
	(footprint ""
		(layer "B.Cu")
		(at 177.423826 -193.794634 180)
		(property "Reference" "R1031"
			(at 0 0 0)
			(layer "B.SilkS")
			(hide yes)
			(effects
				(font
					(size 1.27 1.27)
				)
				(justify mirror)
			)
		)
		(property "Value" ""
			(at 0 0 0)
			(layer "B.Fab")
			(effects
				(font
					(size 1.27 1.27)
				)
				(justify mirror)
			)
		)
		(duplicate_pad_numbers_are_jumpers no)
		(fp_line
			(start 0.7874 0.4064)
			(end 0.7874 -0.4064)
			(stroke
				(width 0.1524)
				(type default)
			)
			(layer "B.SilkS")
		)
		(fp_line
			(start 0.7874 -0.4064)
			(end -0.7874 -0.4064)
			(stroke
				(width 0.1524)
				(type default)
			)
			(layer "B.SilkS")
		)
		(fp_line
			(start -0.7874 0.4064)
			(end 0.7874 0.4064)
			(stroke
				(width 0.1524)
				(type default)
			)
			(layer "B.SilkS")
		)
		(fp_line
			(start -0.7874 -0.4064)
			(end -0.7874 0.4064)
			(stroke
				(width 0.1524)
				(type default)
			)
			(layer "B.SilkS")
		)
		(fp_line
			(start 0.67945 0.3048)
			(end 0.67945 -0.305054)
			(stroke
				(width 0.1)
				(type default)
			)
			(layer "B.Fab")
		)
		(fp_line
			(start 0.67945 -0.305054)
			(end 0.12065 -0.305054)
			(stroke
				(width 0.1)
				(type default)
			)
			(layer "B.Fab")
		)
		(fp_line
			(start 0.12065 0.3048)
			(end 0.67945 0.3048)
			(stroke
				(width 0.1)
				(type default)
			)
			(layer "B.Fab")
		)
		(fp_line
			(start 0.12065 0.2794)
			(end 0.12065 0.3048)
			(stroke
				(width 0.1)
				(type default)
			)
			(layer "B.Fab")
		)
		(fp_line
			(start 0.12065 -0.2794)
			(end -0.12065 -0.2794)
			(stroke
				(width 0.1)
				(type default)
			)
			(layer "B.Fab")
		)
		(fp_line
			(start 0.12065 -0.305054)
			(end 0.12065 -0.2794)
			(stroke
				(width 0.1)
				(type default)
			)
			(layer "B.Fab")
		)
		(fp_line
			(start -0.120396 0.3048)
			(end -0.120396 0.2794)
			(stroke
				(width 0.1)
				(type default)
			)
			(layer "B.Fab")
		)
		(fp_line
			(start -0.120396 0.2794)
			(end 0.12065 0.2794)
			(stroke
				(width 0.1)
				(type default)
			)
			(layer "B.Fab")
		)
		(fp_line
			(start -0.12065 -0.2794)
			(end -0.12065 -0.3048)
			(stroke
				(width 0.1)
				(type default)
			)
			(layer "B.Fab")
		)
		(fp_line
			(start -0.12065 -0.3048)
			(end -0.67945 -0.3048)
			(stroke
				(width 0.1)
				(type default)
			)
			(layer "B.Fab")
		)
		(fp_line
			(start -0.67945 0.3048)
			(end -0.120396 0.3048)
			(stroke
				(width 0.1)
				(type default)
			)
			(layer "B.Fab")
		)
		(fp_line
			(start -0.67945 -0.3048)
			(end -0.67945 0.3048)
			(stroke
				(width 0.1)
				(type default)
			)
			(layer "B.Fab")
		)
		(pad "1" smd circle
			(at 0.40005 0)
			(size 0 0)
			(layers "B.Cu" "B.Mask" "B.Paste")
			(net "SPI_BIC1_MOSI_LS01_DIR3")
		)
		(pad "2" smd circle
			(at -0.40005 0)
			(size 0 0)
			(layers "B.Cu" "B.Mask" "B.Paste")
			(net "P1V8_PEX")
		)
	)
	(footprint ""
		(layer "B.Cu")
		(at 177.649886 -290.199826 90)
		(property "Reference" "C1480"
			(at 0 0 90)
			(layer "B.SilkS")
			(hide yes)
			(effects
				(font
					(size 1.27 1.27)
				)
				(justify mirror)
			)
		)
		(property "Value" ""
			(at 0 0 90)
			(layer "B.Fab")
			(effects
				(font
					(size 1.27 1.27)
				)
				(justify mirror)
			)
		)
		(duplicate_pad_numbers_are_jumpers no)
		(fp_line
			(start 0.299974 -0.150114)
			(end -0.299974 -0.150114)
			(stroke
				(width 0.1)
				(type default)
			)
			(layer "B.Fab")
		)
		(fp_line
			(start -0.299974 -0.150114)
			(end -0.299974 0.150114)
			(stroke
				(width 0.1)
				(type default)
			)
			(layer "B.Fab")
		)
		(fp_line
			(start 0.299974 0.150114)
			(end 0.299974 -0.150114)
			(stroke
				(width 0.1)
				(type default)
			)
			(layer "B.Fab")
		)
		(fp_line
			(start -0.299974 0.150114)
			(end 0.299974 0.150114)
			(stroke
				(width 0.1)
				(type default)
			)
			(layer "B.Fab")
		)
		(pad "1" smd rect
			(at 0.2667 0 270)
			(size 0.3048 0.381)
			(layers "B.Cu" "B.Mask" "B.Paste")
			(net "P0V8_SERDES_VDDA_PEX1")
		)
		(pad "2" smd rect
			(at -0.2667 0 270)
			(size 0.3048 0.381)
			(layers "B.Cu" "B.Mask" "B.Paste")
			(net "GND")
		)
	)
	(footprint ""
		(layer "B.Cu")
		(at 99.130358 -353.718114)
		(property "Reference" "C4180"
			(at 0 0 0)
			(layer "B.SilkS")
			(hide yes)
			(effects
				(font
					(size 1.27 1.27)
				)
				(justify mirror)
			)
		)
		(property "Value" ""
			(at 0 0 0)
			(layer "B.Fab")
			(effects
				(font
					(size 1.27 1.27)
				)
				(justify mirror)
			)
		)
		(duplicate_pad_numbers_are_jumpers no)
		(fp_line
			(start -0.7874 -0.4064)
			(end -0.7874 0.4064)
			(stroke
				(width 0.1524)
				(type default)
			)
			(layer "B.SilkS")
		)
		(fp_line
			(start -0.7874 0.4064)
			(end 0.7874 0.4064)
			(stroke
				(width 0.1524)
				(type default)
			)
			(layer "B.SilkS")
		)
		(fp_line
			(start 0.7874 -0.4064)
			(end -0.7874 -0.4064)
			(stroke
				(width 0.1524)
				(type default)
			)
			(layer "B.SilkS")
		)
		(fp_line
			(start 0.7874 0.4064)
			(end 0.7874 -0.4064)
			(stroke
				(width 0.1524)
				(type default)
			)
			(layer "B.SilkS")
		)
		(fp_line
			(start -0.67945 -0.3048)
			(end -0.67945 0.3048)
			(stroke
				(width 0.1)
				(type default)
			)
			(layer "B.Fab")
		)
		(fp_line
			(start -0.67945 0.3048)
			(end -0.120396 0.3048)
			(stroke
				(width 0.1)
				(type default)
			)
			(layer "B.Fab")
		)
		(fp_line
			(start -0.12065 -0.3048)
			(end -0.67945 -0.3048)
			(stroke
				(width 0.1)
				(type default)
			)
			(layer "B.Fab")
		)
		(fp_line
			(start -0.12065 -0.2794)
			(end -0.12065 -0.3048)
			(stroke
				(width 0.1)
				(type default)
			)
			(layer "B.Fab")
		)
		(fp_line
			(start -0.120396 0.2794)
			(end 0.12065 0.2794)
			(stroke
				(width 0.1)
				(type default)
			)
			(layer "B.Fab")
		)
		(fp_line
			(start -0.120396 0.3048)
			(end -0.120396 0.2794)
			(stroke
				(width 0.1)
				(type default)
			)
			(layer "B.Fab")
		)
		(fp_line
			(start 0.12065 -0.305054)
			(end 0.12065 -0.2794)
			(stroke
				(width 0.1)
				(type default)
			)
			(layer "B.Fab")
		)
		(fp_line
			(start 0.12065 -0.2794)
			(end -0.12065 -0.2794)
			(stroke
				(width 0.1)
				(type default)
			)
			(layer "B.Fab")
		)
		(fp_line
			(start 0.12065 0.2794)
			(end 0.12065 0.3048)
			(stroke
				(width 0.1)
				(type default)
			)
			(layer "B.Fab")
		)
		(fp_line
			(start 0.12065 0.3048)
			(end 0.67945 0.3048)
			(stroke
				(width 0.1)
				(type default)
			)
			(layer "B.Fab")
		)
		(fp_line
			(start 0.67945 -0.305054)
			(end 0.12065 -0.305054)
			(stroke
				(width 0.1)
				(type default)
			)
			(layer "B.Fab")
		)
		(fp_line
			(start 0.67945 0.3048)
			(end 0.67945 -0.305054)
			(stroke
				(width 0.1)
				(type default)
			)
			(layer "B.Fab")
		)
		(pad "1" smd circle
			(at 0.40005 0 180)
			(size 0 0)
			(layers "B.Cu" "B.Mask" "B.Paste")
			(net "P3V3_CLK_BUFFER_9ZXL0451E_S3_VZX3P3")
		)
		(pad "2" smd circle
			(at -0.40005 0 180)
			(size 0 0)
			(layers "B.Cu" "B.Mask" "B.Paste")
			(net "GND")
		)
	)
	(footprint ""
		(layer "B.Cu")
		(at 211.244942 -259.311648 90)
		(property "Reference" "R6349"
			(at 0 0 90)
			(layer "B.SilkS")
			(hide yes)
			(effects
				(font
					(size 1.27 1.27)
				)
				(justify mirror)
			)
		)
		(property "Value" ""
			(at 0 0 90)
			(layer "B.Fab")
			(effects
				(font
					(size 1.27 1.27)
				)
				(justify mirror)
			)
		)
		(duplicate_pad_numbers_are_jumpers no)
		(fp_line
			(start 0.7874 -0.4064)
			(end -0.7874 -0.4064)
			(stroke
				(width 0.1524)
				(type default)
			)
			(layer "B.SilkS")
		)
		(fp_line
			(start -0.7874 -0.4064)
			(end -0.7874 0.4064)
			(stroke
				(width 0.1524)
				(type default)
			)
			(layer "B.SilkS")
		)
		(fp_line
			(start 0.7874 0.4064)
			(end 0.7874 -0.4064)
			(stroke
				(width 0.1524)
				(type default)
			)
			(layer "B.SilkS")
		)
		(fp_line
			(start -0.7874 0.4064)
			(end 0.7874 0.4064)
			(stroke
				(width 0.1524)
				(type default)
			)
			(layer "B.SilkS")
		)
		(fp_line
			(start 0.67945 -0.305054)
			(end 0.12065 -0.305054)
			(stroke
				(width 0.1)
				(type default)
			)
			(layer "B.Fab")
		)
		(fp_line
			(start 0.12065 -0.305054)
			(end 0.12065 -0.2794)
			(stroke
				(width 0.1)
				(type default)
			)
			(layer "B.Fab")
		)
		(fp_line
			(start -0.12065 -0.3048)
			(end -0.67945 -0.3048)
			(stroke
				(width 0.1)
				(type default)
			)
			(layer "B.Fab")
		)
		(fp_line
			(start -0.67945 -0.3048)
			(end -0.67945 0.3048)
			(stroke
				(width 0.1)
				(type default)
			)
			(layer "B.Fab")
		)
		(fp_line
			(start 0.12065 -0.2794)
			(end -0.12065 -0.2794)
			(stroke
				(width 0.1)
				(type default)
			)
			(layer "B.Fab")
		)
		(fp_line
			(start -0.12065 -0.2794)
			(end -0.12065 -0.3048)
			(stroke
				(width 0.1)
				(type default)
			)
			(layer "B.Fab")
		)
		(fp_line
			(start 0.12065 0.2794)
			(end 0.12065 0.3048)
			(stroke
				(width 0.1)
				(type default)
			)
			(layer "B.Fab")
		)
		(fp_line
			(start -0.120396 0.2794)
			(end 0.12065 0.2794)
			(stroke
				(width 0.1)
				(type default)
			)
			(layer "B.Fab")
		)
		(fp_line
			(start 0.67945 0.3048)
			(end 0.67945 -0.305054)
			(stroke
				(width 0.1)
				(type default)
			)
			(layer "B.Fab")
		)
		(fp_line
			(start 0.12065 0.3048)
			(end 0.67945 0.3048)
			(stroke
				(width 0.1)
				(type default)
			)
			(layer "B.Fab")
		)
		(fp_line
			(start -0.120396 0.3048)
			(end -0.120396 0.2794)
			(stroke
				(width 0.1)
				(type default)
			)
			(layer "B.Fab")
		)
		(fp_line
			(start -0.67945 0.3048)
			(end -0.120396 0.3048)
			(stroke
				(width 0.1)
				(type default)
			)
			(layer "B.Fab")
		)
		(pad "1" smd circle
			(at 0.40005 0 270)
			(size 0 0)
			(layers "B.Cu" "B.Mask" "B.Paste")
			(net "P1V8_PEX")
		)
		(pad "2" smd circle
			(at -0.40005 0 270)
			(size 0 0)
			(layers "B.Cu" "B.Mask" "B.Paste")
			(net "SMB_PEX3_MUX_SCL")
		)
	)
	(footprint ""
		(layer "B.Cu")
		(at 185.250074 -296.37482 180)
		(property "Reference" "C1419"
			(at 0 0 0)
			(layer "B.SilkS")
			(hide yes)
			(effects
				(font
					(size 1.27 1.27)
				)
				(justify mirror)
			)
		)
		(property "Value" ""
			(at 0 0 0)
			(layer "B.Fab")
			(effects
				(font
					(size 1.27 1.27)
				)
				(justify mirror)
			)
		)
		(duplicate_pad_numbers_are_jumpers no)
		(fp_line
			(start 0.299974 0.150114)
			(end 0.299974 -0.150114)
			(stroke
				(width 0.1)
				(type default)
			)
			(layer "B.Fab")
		)
		(fp_line
			(start 0.299974 -0.150114)
			(end -0.299974 -0.150114)
			(stroke
				(width 0.1)
				(type default)
			)
			(layer "B.Fab")
		)
		(fp_line
			(start -0.299974 0.150114)
			(end 0.299974 0.150114)
			(stroke
				(width 0.1)
				(type default)
			)
			(layer "B.Fab")
		)
		(fp_line
			(start -0.299974 -0.150114)
			(end -0.299974 0.150114)
			(stroke
				(width 0.1)
				(type default)
			)
			(layer "B.Fab")
		)
		(pad "1" smd rect
			(at 0.2667 0)
			(size 0.3048 0.381)
			(layers "B.Cu" "B.Mask" "B.Paste")
			(net "P0V8_SERDES_VDDA_PEX1")
		)
		(pad "2" smd rect
			(at -0.2667 0)
			(size 0.3048 0.381)
			(layers "B.Cu" "B.Mask" "B.Paste")
			(net "GND")
		)
	)
)
